# TIMECARD (Time Appliance Project (Time Card)) — schematic netlist excerpt (pin names and nets, part order shuffled) for the footprints in the layout excerpt that follows; sources: Cadence DE-HDL packaged netlist, KiCad conversion of R4006-B0001-02_R01.brd

J14  G200_10283_01  pkg S_M_DIL_2X5_P100_V1  page 10
  \1\  = FT4232_FPGA_TCK
  \2\  = SG
  \3\  = FT4232_FPGA_TDO
  \4\  = UNNAMED_127_G2001028301_I427_4
  \5\  = FT4232_FPGA_TMS
  \6\  = NC
  \7\  = NC
  \8\  = NC
  \9\  = FT4232_FPGA_TDI
  \10\  = SG

(kicad_pcb
	(version 20260206)
	(generator "pcbnew")
	(generator_version "10.0")
	(general
		(thickness 1.6)
		(legacy_teardrops no)
	)
	(paper "A4")
	(title_block
		(title "timecard-production-celestica-r4006 — R4006-B0001-02_R01.brd")
		(comment 1 "Time Appliance Project (Time Card) / footprint 187 of 1113 (J14), pads 1-10 of 10")
	)
	(layers
		(0 "F.Cu" signal "TOP")
		(4 "In1.Cu" signal "L02_GND1")
		(6 "In2.Cu" signal "L03_SIG1")
		(8 "In3.Cu" signal "L04_GND2")
		(10 "In4.Cu" signal "L05_VCC1")
		(12 "In5.Cu" signal "L06_VCC2")
		(14 "In6.Cu" signal "L07_GND3")
		(16 "In7.Cu" signal "L08_SIG2")
		(18 "In8.Cu" signal "L09_GND4")
		(2 "B.Cu" signal "BOTTOM")
		(9 "F.Adhes" user "F.Adhesive")
		(11 "B.Adhes" user "B.Adhesive")
		(13 "F.Paste" user "Package Geometry/Pastemask Top")
		(15 "B.Paste" user "Package Geometry/Pastemask Bottom")
		(5 "F.SilkS" user "Ref Des/Silkscreen Top")
		(7 "B.SilkS" user "Ref Des/Silkscreen Bottom")
		(1 "F.Mask" user "Board Geometry/Soldermask Top")
		(3 "B.Mask" user "Board Geometry/Soldermask Bottom")
		(17 "Dwgs.User" user "User.Drawings")
		(19 "Cmts.User" user "User.Comments")
		(21 "Eco1.User" user "User.Eco1")
		(23 "Eco2.User" user "User.Eco2")
		(25 "Edge.Cuts" user "Board Geometry/Outline")
		(27 "Margin" user)
		(31 "F.CrtYd" user "Package Geometry/Place Bound Top")
		(29 "B.CrtYd" user "Package Geometry/Place Bound Bottom")
		(35 "F.Fab" user "Ref Des/Assembly Top")
		(33 "B.Fab" user "Ref Des/Assembly Bottom")
	)
	(footprint ""
		(layer "F.Cu")
		(at 142.4432 -71.6534 90)
		(property "Reference" "J14"
			(at 7.17423 0.4318 0)
			(unlocked yes)
			(layer "F.SilkS")
			(effects
				(font
					(size 0.7874 0.5842)
					(thickness 0.1524)
				)
			)
		)
		(property "Value" ""
			(at 0 0 90)
			(layer "F.Fab")
			(effects
				(font
					(size 1.27 1.27)
				)
			)
		)
		(property "User Part Number" "PARTNUM*"
			(at 0.191262 6.403086 90)
			(unlocked yes)
			(layer "Cmts.User")
			(hide yes)
			(effects
				(font
					(size 0.7874 0.5842)
					(thickness 0.1524)
				)
			)
		)
		(property "Device Type" "G200_10283_01-G200-10283-01"
			(at 0.241808 5.437378 90)
			(unlocked yes)
			(layer "F.Fab")
			(hide yes)
			(effects
				(font
					(size 0.7874 0.5842)
					(thickness 0.1524)
				)
			)
		)
		(duplicate_pad_numbers_are_jumpers no)
		(pad "1" smd rect
			(at -5.08 2.605024 90)
			(size 1.27 3.556)
			(layers "F.Cu" "F.Mask" "F.Paste")
			(net "FT4232_FPGA_TCK")
		)
		(pad "2" smd rect
			(at -5.08 -2.605024 90)
			(size 1.27 3.556)
			(layers "F.Cu" "F.Mask" "F.Paste")
			(net "SG")
		)
		(pad "3" smd rect
			(at -2.54 2.605024 90)
			(size 1.27 3.556)
			(layers "F.Cu" "F.Mask" "F.Paste")
			(net "FT4232_FPGA_TDO")
		)
		(pad "4" smd rect
			(at -2.54 -2.605024 90)
			(size 1.27 3.556)
			(layers "F.Cu" "F.Mask" "F.Paste")
			(net "UNNAMED_127_G2001028301_I427_4")
		)
		(pad "5" smd rect
			(at 0 2.605024 90)
			(size 1.27 3.556)
			(layers "F.Cu" "F.Mask" "F.Paste")
			(net "FT4232_FPGA_TMS")
		)
		(pad "6" smd rect
			(at 0 -2.605024 90)
			(size 1.27 3.556)
			(layers "F.Cu" "F.Mask" "F.Paste")
			(net "Net_625")
		)
		(pad "7" smd rect
			(at 2.54 2.605024 90)
			(size 1.27 3.556)
			(layers "F.Cu" "F.Mask" "F.Paste")
			(net "Net_626")
		)
		(pad "8" smd rect
			(at 2.54 -2.605024 90)
			(size 1.27 3.556)
			(layers "F.Cu" "F.Mask" "F.Paste")
			(net "Net_627")
		)
		(pad "9" smd rect
			(at 5.08 2.605024 90)
			(size 1.27 3.556)
			(layers "F.Cu" "F.Mask" "F.Paste")
			(net "FT4232_FPGA_TDI")
		)
		(pad "10" smd rect
			(at 5.08 -2.605024 90)
			(size 1.27 3.556)
			(layers "F.Cu" "F.Mask" "F.Paste")
			(net "SG")
		)
	)
)
